# S9S_MB_2U (Grand Teton) — schematic netlist excerpt (pin names and nets, part order shuffled) for the footprints in the layout excerpt that follows; sources: Cadence DE-HDL packaged netlist, KiCad conversion of 03242023_DA0F0TMBIJ0_F0T_Motherboard_J_brd_V01_OCP.brd

R4187  Q_RES  1K 1% CHIP  pkg 0402LF  page 170 : A = U272_2_ADD2 ; B = GND
R4672  Q_RES  10K 1% EMPTY  pkg 0402LF  page 306 : A = P3V3_AUX ; B = A_HSC_LOW_GATE

(kicad_pcb
	(version 20260206)
	(generator "pcbnew")
	(generator_version "10.0")
	(general
		(thickness 1.6)
		(legacy_teardrops no)
	)
	(paper "A4")
	(title_block
		(title "03242023_DA0F0TMBIJ0_F0T_Motherboard_J_brd_V01_OCP.brd")
		(comment 1 "Grand Teton / footprints 3373-3374 of 6105")
	)
	(layers
		(0 "F.Cu" signal "TOP")
		(4 "In1.Cu" signal "GND")
		(6 "In2.Cu" signal "IN1")
		(8 "In3.Cu" signal "GND1")
		(10 "In4.Cu" signal "IN2")
		(12 "In5.Cu" signal "GND2")
		(14 "In6.Cu" signal "IN3")
		(16 "In7.Cu" signal "GND3")
		(18 "In8.Cu" signal "VCC")
		(20 "In9.Cu" signal "VCC1")
		(22 "In10.Cu" signal "GND4")
		(24 "In11.Cu" signal "IN4")
		(26 "In12.Cu" signal "GND5")
		(28 "In13.Cu" signal "IN5")
		(30 "In14.Cu" signal "GND6")
		(32 "In15.Cu" signal "IN6")
		(34 "In16.Cu" signal "GND7")
		(2 "B.Cu" signal "BOTTOM")
		(9 "F.Adhes" user "F.Adhesive")
		(11 "B.Adhes" user "B.Adhesive")
		(13 "F.Paste" user "Package Geometry/Pastemask Top")
		(15 "B.Paste" user "Package Geometry/Pastemask Bottom")
		(5 "F.SilkS" user "Ref Des/Silkscreen Top")
		(7 "B.SilkS" user "Ref Des/Silkscreen Bottom")
		(1 "F.Mask" user "Board Geometry/Soldermask Top")
		(3 "B.Mask" user "Board Geometry/Soldermask Bottom")
		(17 "Dwgs.User" user "User.Drawings")
		(19 "Cmts.User" user "User.Comments")
		(21 "Eco1.User" user "User.Eco1")
		(23 "Eco2.User" user "User.Eco2")
		(25 "Edge.Cuts" user "Board Geometry/Outline")
		(27 "Margin" user)
		(31 "F.CrtYd" user "Package Geometry/Place Bound Top")
		(29 "B.CrtYd" user "Package Geometry/Place Bound Bottom")
		(35 "F.Fab" user "Ref Des/Assembly Top")
		(33 "B.Fab" user "Ref Des/Assembly Bottom")
	)
	(footprint ""
		(layer "F.Cu")
		(at 96.138238 -414.75533 -90)
		(property "Reference" "R4187"
			(at 0 0 270)
			(layer "F.SilkS")
			(hide yes)
			(effects
				(font
					(size 1.27 1.27)
				)
			)
		)
		(property "Value" ""
			(at 0 0 270)
			(layer "F.Fab")
			(effects
				(font
					(size 1.27 1.27)
				)
			)
		)
		(duplicate_pad_numbers_are_jumpers no)
		(fp_line
			(start -0.7874 0.4064)
			(end -0.7874 -0.4064)
			(stroke
				(width 0.1524)
				(type default)
			)
			(layer "F.SilkS")
		)
		(fp_line
			(start 0.7874 0.4064)
			(end -0.7874 0.4064)
			(stroke
				(width 0.1524)
				(type default)
			)
			(layer "F.SilkS")
		)
		(fp_line
			(start -0.7874 -0.4064)
			(end 0.7874 -0.4064)
			(stroke
				(width 0.1524)
				(type default)
			)
			(layer "F.SilkS")
		)
		(fp_line
			(start 0.7874 -0.4064)
			(end 0.7874 0.4064)
			(stroke
				(width 0.1524)
				(type default)
			)
			(layer "F.SilkS")
		)
		(fp_line
			(start -0.67945 0.3048)
			(end -0.67945 -0.305054)
			(stroke
				(width 0.1)
				(type default)
			)
			(layer "F.Fab")
		)
		(fp_line
			(start -0.12065 0.3048)
			(end -0.67945 0.3048)
			(stroke
				(width 0.1)
				(type default)
			)
			(layer "F.Fab")
		)
		(fp_line
			(start 0.120396 0.3048)
			(end 0.120396 0.2794)
			(stroke
				(width 0.1)
				(type default)
			)
			(layer "F.Fab")
		)
		(fp_line
			(start 0.67945 0.3048)
			(end 0.120396 0.3048)
			(stroke
				(width 0.1)
				(type default)
			)
			(layer "F.Fab")
		)
		(fp_line
			(start -0.12065 0.2794)
			(end -0.12065 0.3048)
			(stroke
				(width 0.1)
				(type default)
			)
			(layer "F.Fab")
		)
		(fp_line
			(start 0.120396 0.2794)
			(end -0.12065 0.2794)
			(stroke
				(width 0.1)
				(type default)
			)
			(layer "F.Fab")
		)
		(fp_line
			(start -0.12065 -0.2794)
			(end 0.12065 -0.2794)
			(stroke
				(width 0.1)
				(type default)
			)
			(layer "F.Fab")
		)
		(fp_line
			(start 0.12065 -0.2794)
			(end 0.12065 -0.3048)
			(stroke
				(width 0.1)
				(type default)
			)
			(layer "F.Fab")
		)
		(fp_line
			(start 0.12065 -0.3048)
			(end 0.67945 -0.3048)
			(stroke
				(width 0.1)
				(type default)
			)
			(layer "F.Fab")
		)
		(fp_line
			(start 0.67945 -0.3048)
			(end 0.67945 0.3048)
			(stroke
				(width 0.1)
				(type default)
			)
			(layer "F.Fab")
		)
		(fp_line
			(start -0.67945 -0.305054)
			(end -0.12065 -0.305054)
			(stroke
				(width 0.1)
				(type default)
			)
			(layer "F.Fab")
		)
		(fp_line
			(start -0.12065 -0.305054)
			(end -0.12065 -0.2794)
			(stroke
				(width 0.1)
				(type default)
			)
			(layer "F.Fab")
		)
		(pad "1" smd circle
			(at -0.40005 0 270)
			(size 0 0)
			(layers "F.Cu" "F.Mask" "F.Paste")
			(net "U272_2_ADD2")
		)
		(pad "2" smd circle
			(at 0.40005 0 270)
			(size 0 0)
			(layers "F.Cu" "F.Mask" "F.Paste")
			(net "GND")
		)
	)
	(footprint ""
		(layer "F.Cu")
		(at 277.230078 -417.2839 90)
		(property "Reference" "R4672"
			(at 0 0 90)
			(layer "F.SilkS")
			(hide yes)
			(effects
				(font
					(size 1.27 1.27)
				)
			)
		)
		(property "Value" ""
			(at 0 0 90)
			(layer "F.Fab")
			(effects
				(font
					(size 1.27 1.27)
				)
			)
		)
		(duplicate_pad_numbers_are_jumpers no)
		(fp_line
			(start 0.7874 -0.4064)
			(end 0.7874 0.4064)
			(stroke
				(width 0.1524)
				(type default)
			)
			(layer "F.SilkS")
		)
		(fp_line
			(start -0.7874 -0.4064)
			(end 0.7874 -0.4064)
			(stroke
				(width 0.1524)
				(type default)
			)
			(layer "F.SilkS")
		)
		(fp_line
			(start 0.7874 0.4064)
			(end -0.7874 0.4064)
			(stroke
				(width 0.1524)
				(type default)
			)
			(layer "F.SilkS")
		)
		(fp_line
			(start -0.7874 0.4064)
			(end -0.7874 -0.4064)
			(stroke
				(width 0.1524)
				(type default)
			)
			(layer "F.SilkS")
		)
		(fp_line
			(start -0.12065 -0.305054)
			(end -0.12065 -0.2794)
			(stroke
				(width 0.1)
				(type default)
			)
			(layer "F.Fab")
		)
		(fp_line
			(start -0.67945 -0.305054)
			(end -0.12065 -0.305054)
			(stroke
				(width 0.1)
				(type default)
			)
			(layer "F.Fab")
		)
		(fp_line
			(start 0.67945 -0.3048)
			(end 0.67945 0.3048)
			(stroke
				(width 0.1)
				(type default)
			)
			(layer "F.Fab")
		)
		(fp_line
			(start 0.12065 -0.3048)
			(end 0.67945 -0.3048)
			(stroke
				(width 0.1)
				(type default)
			)
			(layer "F.Fab")
		)
		(fp_line
			(start 0.12065 -0.2794)
			(end 0.12065 -0.3048)
			(stroke
				(width 0.1)
				(type default)
			)
			(layer "F.Fab")
		)
		(fp_line
			(start -0.12065 -0.2794)
			(end 0.12065 -0.2794)
			(stroke
				(width 0.1)
				(type default)
			)
			(layer "F.Fab")
		)
		(fp_line
			(start 0.120396 0.2794)
			(end -0.12065 0.2794)
			(stroke
				(width 0.1)
				(type default)
			)
			(layer "F.Fab")
		)
		(fp_line
			(start -0.12065 0.2794)
			(end -0.12065 0.3048)
			(stroke
				(width 0.1)
				(type default)
			)
			(layer "F.Fab")
		)
		(fp_line
			(start 0.67945 0.3048)
			(end 0.120396 0.3048)
			(stroke
				(width 0.1)
				(type default)
			)
			(layer "F.Fab")
		)
		(fp_line
			(start 0.120396 0.3048)
			(end 0.120396 0.2794)
			(stroke
				(width 0.1)
				(type default)
			)
			(layer "F.Fab")
		)
		(fp_line
			(start -0.12065 0.3048)
			(end -0.67945 0.3048)
			(stroke
				(width 0.1)
				(type default)
			)
			(layer "F.Fab")
		)
		(fp_line
			(start -0.67945 0.3048)
			(end -0.67945 -0.305054)
			(stroke
				(width 0.1)
				(type default)
			)
			(layer "F.Fab")
		)
		(pad "1" smd circle
			(at -0.40005 0 90)
			(size 0 0)
			(layers "F.Cu" "F.Mask" "F.Paste")
			(net "P3V3_AUX")
		)
		(pad "2" smd circle
			(at 0.40005 0 90)
			(size 0 0)
			(layers "F.Cu" "F.Mask" "F.Paste")
			(net "A_HSC_LOW_GATE")
		)
	)
)
